(kicad_pcb
	(version 20241229)
	(generator "pcbnew")
	(generator_version "9.0")
	(general
		(thickness 1.711)
		(legacy_teardrops no)
	)
	(paper "A4")
	(title_block
		(title "Antmicro Baseboard for Jetson AGX Thor")
		(date "2026-02-18")
		(rev "1.1.0")
		(company "Antmicro Ltd")
		(comment 1 "www.antmicro.com")
		(comment 9 "footprints 42-45 of 1170")
	)
	(layers
		(0 "F.Cu" signal)
		(4 "In1.Cu" signal)
		(6 "In2.Cu" signal)
		(8 "In3.Cu" signal)
		(10 "In4.Cu" jumper)
		(12 "In5.Cu" signal)
		(14 "In6.Cu" signal)
		(16 "In7.Cu" signal)
		(18 "In8.Cu" signal)
		(2 "B.Cu" signal)
		(9 "F.Adhes" user "F.Adhesive")
		(11 "B.Adhes" user "B.Adhesive")
		(13 "F.Paste" user)
		(15 "B.Paste" user)
		(5 "F.SilkS" user "F.Silkscreen")
		(7 "B.SilkS" user "B.Silkscreen")
		(1 "F.Mask" user)
		(3 "B.Mask" user)
		(17 "Dwgs.User" user "User.Drawings")
		(19 "Cmts.User" user "User.Comments")
		(21 "Eco1.User" user "User.Eco1")
		(23 "Eco2.User" user "User.Eco2")
		(25 "Edge.Cuts" user)
		(27 "Margin" user)
		(31 "F.CrtYd" user "F.Courtyard")
		(29 "B.CrtYd" user "B.Courtyard")
		(35 "F.Fab" user)
		(33 "B.Fab" user)
	)
	(footprint "antmicro-footprints:C_0402_1005Metric"
		(layer "F.Cu")
		(at 128.6 132.8)
		(descr "Capacitor SMD 0402")
		(tags "capacitor SMD 0402")
		(property "Reference" "C5"
			(at -2.63 0.4 0)
			(layer "F.SilkS")
			(effects
				(font
					(size 0.7 0.7)
					(thickness 0.15)
				)
				(justify left bottom)
			)
		)
		(property "Value" "C_100n_0402"
			(at -1.022927 2.155213 0)
			(layer "F.Fab")
			(effects
				(font
					(size 0.7 0.7)
					(thickness 0.15)
				)
				(justify left bottom)
			)
		)
		(property "Datasheet" "https://www.murata.com/products/productdetail?partno=GRM155R61H104KE14%23"
			(at 0 0 0)
			(layer "F.Fab")
			(hide yes)
			(effects
				(font
					(size 1.27 1.27)
					(thickness 0.15)
				)
			)
		)
		(property "Description" "SMD Multilayer Ceramic Capacitor, 0.1 µF, 50 V, 0402 [1005 Metric], ± 10%, X5R, GRM Series"
			(at 0 0 0)
			(layer "F.Fab")
			(hide yes)
			(effects
				(font
					(size 1.27 1.27)
					(thickness 0.15)
				)
			)
		)
		(property "Manufacturer" "Murata"
			(at 0 0 0)
			(unlocked yes)
			(layer "F.Fab")
			(hide yes)
			(effects
				(font
					(size 1 1)
					(thickness 0.15)
				)
			)
		)
		(property "MPN" "GRM155R61H104KE14D"
			(at 0 0 0)
			(unlocked yes)
			(layer "F.Fab")
			(hide yes)
			(effects
				(font
					(size 1 1)
					(thickness 0.15)
				)
			)
		)
		(property "Val" "100n"
			(at 0 0 0)
			(unlocked yes)
			(layer "F.Fab")
			(hide yes)
			(effects
				(font
					(size 1 1)
					(thickness 0.15)
				)
			)
		)
		(property "License" "Apache-2.0"
			(at 0 0 0)
			(unlocked yes)
			(layer "F.Fab")
			(hide yes)
			(effects
				(font
					(size 1 1)
					(thickness 0.15)
				)
			)
		)
		(property "Author" "Antmicro"
			(at 0 0 0)
			(unlocked yes)
			(layer "F.Fab")
			(hide yes)
			(effects
				(font
					(size 1 1)
					(thickness 0.15)
				)
			)
		)
		(property "Voltage" "50V"
			(at 0 0 0)
			(unlocked yes)
			(layer "F.Fab")
			(hide yes)
			(effects
				(font
					(size 1 1)
					(thickness 0.15)
				)
			)
		)
		(property "Dielectric" "X5R"
			(at 0 0 0)
			(unlocked yes)
			(layer "F.Fab")
			(hide yes)
			(effects
				(font
					(size 1 1)
					(thickness 0.15)
				)
			)
		)
		(sheetname "/Expansion connector/")
		(sheetfile "expansion_connector.kicad_sch")
		(attr smd)
		(fp_poly
			(pts
				(xy -0.925 -0.47) (xy -0.925 0.47) (xy 0.925 0.47) (xy 0.925 -0.47)
			)
			(stroke
				(width 0.05)
				(type default)
			)
			(fill no)
			(layer "F.CrtYd")
		)
		(fp_line
			(start -0.494 -0.25)
			(end 0.504 -0.25)
			(stroke
				(width 0.15)
				(type solid)
			)
			(layer "F.Fab")
		)
		(fp_line
			(start -0.494 0.248)
			(end -0.494 -0.25)
			(stroke
				(width 0.15)
				(type solid)
			)
			(layer "F.Fab")
		)
		(fp_line
			(start 0.504 -0.25)
			(end 0.504 0.248)
			(stroke
				(width 0.15)
				(type solid)
			)
			(layer "F.Fab")
		)
		(fp_line
			(start 0.504 0.248)
			(end -0.494 0.248)
			(stroke
				(width 0.15)
				(type solid)
			)
			(layer "F.Fab")
		)
		(fp_text user "Author: Antmicro"
			(at -0.939 3.399 0)
			(layer "F.Fab")
			(effects
				(font
					(size 0.7 0.7)
					(thickness 0.15)
				)
				(justify left bottom)
			)
		)
		(fp_text user "${REFERENCE}"
			(at -0.939 4.599 0)
			(layer "F.Fab")
			(effects
				(font
					(size 0.7 0.7)
					(thickness 0.15)
				)
				(justify left bottom)
			)
		)
		(fp_text user "License: Apache-2.0"
			(at -0.939 5.799 0)
			(layer "F.Fab")
			(effects
				(font
					(size 0.7 0.7)
					(thickness 0.15)
				)
				(justify left bottom)
			)
		)
		(pad "1" smd roundrect
			(at -0.48 0)
			(size 0.59 0.64)
			(layers "F.Cu" "F.Mask" "F.Paste")
			(roundrect_rratio 0.25)
			(net 1 "GND")
			(pintype "passive")
		)
		(pad "2" smd roundrect
			(at 0.48 0)
			(size 0.59 0.64)
			(layers "F.Cu" "F.Mask" "F.Paste")
			(roundrect_rratio 0.25)
			(net 148 "/Expansion connector/+3V3_AUX")
			(pintype "passive")
		)
	)
	(footprint "antmicro-footprints:C_0805_2012Metric"
		(layer "F.Cu")
		(at 176.33 142.41 90)
		(descr "Capacitor SMD 0805")
		(tags "capacitor SMD 0805")
		(property "Reference" "C309"
			(at 1.87 -0.26 90)
			(layer "F.SilkS")
			(effects
				(font
					(size 0.7 0.7)
					(thickness 0.15)
				)
				(justify left bottom)
			)
		)
		(property "Value" "C_22u_25V_0805"
			(at -2.055717 1.963152 90)
			(layer "F.Fab")
			(effects
				(font
					(size 0.7 0.7)
					(thickness 0.15)
				)
				(justify left bottom)
			)
		)
		(property "Datasheet" "https://product.samsungsem.com/mlcc/CL21A226MAYNNN.do"
			(at 0 0 90)
			(layer "F.Fab")
			(hide yes)
			(effects
				(font
					(size 1.27 1.27)
					(thickness 0.15)
				)
			)
		)
		(property "Description" "SMT Multilayer Ceramic Capacitor, 22uF, +/-20%, 25V, X5R, 0805 [2012 Metric]"
			(at 0 0 90)
			(layer "F.Fab")
			(hide yes)
			(effects
				(font
					(size 1.27 1.27)
					(thickness 0.15)
				)
			)
		)
		(property "Manufacturer" "Samsung Electro-Mechanics"
			(at 0 0 90)
			(unlocked yes)
			(layer "F.Fab")
			(hide yes)
			(effects
				(font
					(size 1 1)
					(thickness 0.15)
				)
			)
		)
		(property "MPN" "CL21A226MAYNNNE"
			(at 0 0 90)
			(unlocked yes)
			(layer "F.Fab")
			(hide yes)
			(effects
				(font
					(size 1 1)
					(thickness 0.15)
				)
			)
		)
		(property "Val" "22u"
			(at 0 0 90)
			(unlocked yes)
			(layer "F.Fab")
			(hide yes)
			(effects
				(font
					(size 1 1)
					(thickness 0.15)
				)
			)
		)
		(property "License" "Apache-2.0"
			(at 0 0 90)
			(unlocked yes)
			(layer "F.Fab")
			(hide yes)
			(effects
				(font
					(size 1 1)
					(thickness 0.15)
				)
			)
		)
		(property "Author" "Antmicro"
			(at 0 0 90)
			(unlocked yes)
			(layer "F.Fab")
			(hide yes)
			(effects
				(font
					(size 1 1)
					(thickness 0.15)
				)
			)
		)
		(property "Voltage" "25V"
			(at 0 0 90)
			(unlocked yes)
			(layer "F.Fab")
			(hide yes)
			(effects
				(font
					(size 1 1)
					(thickness 0.15)
				)
			)
		)
		(property "Dielectric" "X5R"
			(at 0 0 90)
			(unlocked yes)
			(layer "F.Fab")
			(hide yes)
			(effects
				(font
					(size 1 1)
					(thickness 0.15)
				)
			)
		)
		(property "Public" "False"
			(at 0 0 90)
			(unlocked yes)
			(layer "F.Fab")
			(hide yes)
			(effects
				(font
					(size 1 1)
					(thickness 0.15)
				)
			)
		)
		(sheetname "/DCDC/")
		(sheetfile "dcdc.kicad_sch")
		(attr smd)
		(fp_line
			(start -0.3 -0.7)
			(end 0.3 -0.7)
			(stroke
				(width 0.15)
				(type solid)
			)
			(layer "F.SilkS")
		)
		(fp_line
			(start -0.3 0.7)
			(end 0.3 0.7)
			(stroke
				(width 0.15)
				(type solid)
			)
			(layer "F.SilkS")
		)
		(fp_rect
			(start 1.95 -0.9)
			(end -1.95 0.9)
			(stroke
				(width 0.05)
				(type default)
			)
			(fill no)
			(layer "F.CrtYd")
		)
		(fp_rect
			(start -0.95 -0.675)
			(end 0.95 0.675)
			(stroke
				(width 0.15)
				(type solid)
			)
			(fill no)
			(layer "F.Fab")
		)
		(fp_text user "${REFERENCE}"
			(at -1.9 3.947 90)
			(layer "F.Fab")
			(effects
				(font
					(size 0.7 0.7)
					(thickness 0.15)
				)
				(justify left bottom)
			)
		)
		(fp_text user "License: Apache-2.0"
			(at -1.9 4.947 90)
			(layer "F.Fab")
			(effects
				(font
					(size 0.7 0.7)
					(thickness 0.15)
				)
				(justify left bottom)
			)
		)
		(fp_text user "Author: Antmicro"
			(at -1.9 5.947 90)
			(layer "F.Fab")
			(effects
				(font
					(size 0.7 0.7)
					(thickness 0.15)
				)
				(justify left bottom)
			)
		)
		(pad "1" smd roundrect
			(at -1.1 0 90)
			(size 1.2 1.3)
			(layers "F.Cu" "F.Mask" "F.Paste")
			(roundrect_rratio 0.25)
			(net 1 "GND")
			(pintype "passive")
		)
		(pad "2" smd roundrect
			(at 1.1 0 90)
			(size 1.2 1.3)
			(layers "F.Cu" "F.Mask" "F.Paste")
			(roundrect_rratio 0.25)
			(net 13 "VCC")
			(pintype "passive")
		)
	)
	(footprint "antmicro-footprints:R_0402_1005Metric"
		(layer "F.Cu")
		(at 189.49 124.92 90)
		(descr "Resistor SMD 0402")
		(tags "resistor SMD 0402")
		(property "Reference" "R9"
			(at -0.28 1.41 90)
			(layer "F.SilkS")
			(effects
				(font
					(size 0.7 0.7)
					(thickness 0.15)
				)
				(justify left bottom)
			)
		)
		(property "Value" "R_11k_0402"
			(at -1.011843 1.772047 90)
			(layer "F.Fab")
			(effects
				(font
					(size 0.7 0.7)
					(thickness 0.15)
				)
				(justify left bottom)
			)
		)
		(property "Datasheet" "https://www.bourns.com/docs/product-datasheets/cr.pdf"
			(at 0 0 90)
			(layer "F.Fab")
			(hide yes)
			(effects
				(font
					(size 1.27 1.27)
					(thickness 0.15)
				)
			)
		)
		(property "Description" "SMD Chip Resistor, 11 kohm, ± 1%, 62.5 mW, 0402 [1005 Metric], Thick Film, General Purpose"
			(at 0 0 90)
			(layer "F.Fab")
			(hide yes)
			(effects
				(font
					(size 1.27 1.27)
					(thickness 0.15)
				)
			)
		)
		(property "MPN" "CR0402-FX-1102GLF"
			(at 0 0 90)
			(unlocked yes)
			(layer "F.Fab")
			(hide yes)
			(effects
				(font
					(size 1 1)
					(thickness 0.15)
				)
			)
		)
		(property "Manufacturer" "Bourns"
			(at 0 0 90)
			(unlocked yes)
			(layer "F.Fab")
			(hide yes)
			(effects
				(font
					(size 1 1)
					(thickness 0.15)
				)
			)
		)
		(property "License" "Apache-2.0"
			(at 0 0 90)
			(unlocked yes)
			(layer "F.Fab")
			(hide yes)
			(effects
				(font
					(size 1 1)
					(thickness 0.15)
				)
			)
		)
		(property "Author" "Antmicro"
			(at 0 0 90)
			(unlocked yes)
			(layer "F.Fab")
			(hide yes)
			(effects
				(font
					(size 1 1)
					(thickness 0.15)
				)
			)
		)
		(property "Val" "11k"
			(at 0 0 90)
			(unlocked yes)
			(layer "F.Fab")
			(hide yes)
			(effects
				(font
					(size 1 1)
					(thickness 0.15)
				)
			)
		)
		(property "Tolerance" "1%"
			(at 0 0 90)
			(unlocked yes)
			(layer "F.Fab")
			(hide yes)
			(effects
				(font
					(size 1 1)
					(thickness 0.15)
				)
			)
		)
		(component_classes
			(class "DCDC_1V15")
		)
		(sheetname "/DCDC/")
		(sheetfile "dcdc.kicad_sch")
		(attr smd)
		(fp_rect
			(start -0.925 -0.47)
			(end 0.925 0.47)
			(stroke
				(width 0.05)
				(type default)
			)
			(fill no)
			(layer "F.CrtYd")
		)
		(fp_rect
			(start -0.5 -0.25)
			(end 0.5 0.25)
			(stroke
				(width 0.15)
				(type solid)
			)
			(fill no)
			(layer "F.Fab")
		)
		(fp_text user "License: Apache-2.0"
			(at -0.95 5.169 90)
			(layer "F.Fab")
			(effects
				(font
					(size 0.7 0.7)
					(thickness 0.15)
				)
				(justify left bottom)
			)
		)
		(fp_text user "${REFERENCE}"
			(at -0.95 3.168 90)
			(layer "F.Fab")
			(effects
				(font
					(size 0.7 0.7)
					(thickness 0.15)
				)
				(justify left bottom)
			)
		)
		(fp_text user "Author: Antmicro"
			(at -0.95 4.169 90)
			(layer "F.Fab")
			(effects
				(font
					(size 0.7 0.7)
					(thickness 0.15)
				)
				(justify left bottom)
			)
		)
		(pad "1" smd roundrect
			(at -0.48 0 90)
			(size 0.59 0.64)
			(layers "F.Cu" "F.Mask" "F.Paste")
			(roundrect_rratio 0.25)
			(net 1232 "/DCDC/1V15_FB")
			(pintype "passive")
		)
		(pad "2" smd roundrect
			(at 0.48 0 90)
			(size 0.59 0.64)
			(layers "F.Cu" "F.Mask" "F.Paste")
			(roundrect_rratio 0.25)
			(net 280 "/DCDC/1V15_OUT")
			(pintype "passive")
		)
	)
	(footprint "antmicro-footprints:SOT-523"
		(layer "F.Cu")
		(at 96.9 63.5 90)
		(property "Reference" "Q30"
			(at -1 2.1 90)
			(layer "F.SilkS")
			(effects
				(font
					(size 0.7 0.7)
					(thickness 0.15)
				)
				(justify left bottom)
			)
		)
		(property "Value" "DMG1012T-7"
			(at 0.1 1.824 90)
			(layer "F.Fab")
			(effects
				(font
					(size 0.7 0.7)
					(thickness 0.15)
				)
				(justify left bottom)
			)
		)
		(property "Datasheet" "https://www.diodes.com/assets/Datasheets/ds31783.pdf"
			(at 0 0 90)
			(layer "F.Fab")
			(hide yes)
			(effects
				(font
					(size 1.27 1.27)
					(thickness 0.15)
				)
			)
		)
		(property "Description" "Power MOSFET, N Channel, 20 V, 630 mA, 0.3 ohm, SOT-523, Surface Mount"
			(at 0 0 90)
			(layer "F.Fab")
			(hide yes)
			(effects
				(font
					(size 1.27 1.27)
					(thickness 0.15)
				)
			)
		)
		(property "MPN" "DMG1012T-7"
			(at 0 0 90)
			(unlocked yes)
			(layer "F.Fab")
			(hide yes)
			(effects
				(font
					(size 1 1)
					(thickness 0.15)
				)
			)
		)
		(property "Manufacturer" "Diodes Incorporated"
			(at 0 0 90)
			(unlocked yes)
			(layer "F.Fab")
			(hide yes)
			(effects
				(font
					(size 1 1)
					(thickness 0.15)
				)
			)
		)
		(property "Author" "Antmicro"
			(at 0 0 90)
			(unlocked yes)
			(layer "F.Fab")
			(hide yes)
			(effects
				(font
					(size 1 1)
					(thickness 0.15)
				)
			)
		)
		(property "License" "Apache-2.0"
			(at 0 0 90)
			(unlocked yes)
			(layer "F.Fab")
			(hide yes)
			(effects
				(font
					(size 1 1)
					(thickness 0.15)
				)
			)
		)
		(sheetname "/SoM_Power/")
		(sheetfile "som_power.kicad_sch")
		(attr smd)
		(fp_line
			(start -0.277 -0.551)
			(end -0.277 -0.75)
			(stroke
				(width 0.15)
				(type solid)
			)
			(layer "F.SilkS")
		)
		(fp_line
			(start -0.725 -0.551)
			(end -0.277 -0.551)
			(stroke
				(width 0.15)
				(type solid)
			)
			(layer "F.SilkS")
		)
		(fp_line
			(start -0.927 -0.351)
			(end -0.725 -0.551)
			(stroke
				(width 0.15)
				(type solid)
			)
			(layer "F.SilkS")
		)
		(fp_line
			(start -0.927 -0.051)
			(end -0.927 -0.351)
			(stroke
				(width 0.15)
				(type solid)
			)
			(layer "F.SilkS")
		)
		(fp_circle
			(center -0.9652 0.9652)
			(end -0.9152 0.9652)
			(stroke
				(width 0.15)
				(type solid)
			)
			(fill yes)
			(layer "F.SilkS")
		)
		(fp_line
			(start 1.1 -1.16)
			(end 1.1 1.15)
			(stroke
				(width 0.05)
				(type solid)
			)
			(layer "F.CrtYd")
		)
		(fp_line
			(start -1.12 -1.16)
			(end 1.1 -1.16)
			(stroke
				(width 0.05)
				(type solid)
			)
			(layer "F.CrtYd")
		)
		(fp_line
			(start -1.12 -1.16)
			(end -1.12 1.15)
			(stroke
				(width 0.05)
				(type solid)
			)
			(layer "F.CrtYd")
		)
		(fp_line
			(start -1.12 1.15)
			(end 1.1 1.15)
			(stroke
				(width 0.05)
				(type solid)
			)
			(layer "F.CrtYd")
		)
		(fp_line
			(start 0.8 -0.425)
			(end -0.652 -0.425)
			(stroke
				(width 0.15)
				(type solid)
			)
			(layer "F.Fab")
		)
		(fp_line
			(start 0.8 -0.425)
			(end 0.8 0.424)
			(stroke
				(width 0.15)
				(type solid)
			)
			(layer "F.Fab")
		)
		(fp_line
			(start -0.652 -0.425)
			(end -0.802 -0.276)
			(stroke
				(width 0.15)
				(type solid)
			)
			(layer "F.Fab")
		)
		(fp_line
			(start -0.802 -0.276)
			(end -0.802 0.424)
			(stroke
				(width 0.15)
				(type solid)
			)
			(layer "F.Fab")
		)
		(fp_line
			(start 0.8 0.424)
			(end -0.802 0.424)
			(stroke
				(width 0.15)
				(type solid)
			)
			(layer "F.Fab")
		)
		(fp_circle
			(center -0.9652 0.9652)
			(end -0.9144 0.9652)
			(stroke
				(width 0.15)
				(type solid)
			)
			(fill no)
			(layer "F.Fab")
		)
		(fp_text user "${REFERENCE}"
			(at -1.12 3.824 90)
			(layer "F.Fab")
			(effects
				(font
					(size 0.7 0.7)
					(thickness 0.15)
				)
				(justify left bottom)
			)
		)
		(fp_text user "Author: Antmicro"
			(at -1.12 6.224 90)
			(layer "F.Fab")
			(effects
				(font
					(size 0.7 0.7)
					(thickness 0.15)
				)
				(justify left bottom)
			)
		)
		(fp_text user "License: Apache-2.0"
			(at -1.12 5.024 90)
			(layer "F.Fab")
			(effects
				(font
					(size 0.7 0.7)
					(thickness 0.15)
				)
				(justify left bottom)
			)
		)
		(pad "1" smd rect
			(at -0.5 0.65 90)
			(size 0.4 0.51)
			(layers "F.Cu" "F.Mask" "F.Paste")
			(net 11 "+1V8")
			(pinfunction "G")
			(pintype "input")
		)
		(pad "2" smd rect
			(at 0.498 0.65 90)
			(size 0.4 0.51)
			(layers "F.Cu" "F.Mask" "F.Paste")
			(net 1235 "Net-(Q30-S)")
			(pinfunction "S")
			(pintype "passive")
		)
		(pad "3" smd rect
			(at 0 -0.652 90)
			(size 0.4 0.51)
			(layers "F.Cu" "F.Mask" "F.Paste")
			(net 1379 "Net-(Q30-D)")
			(pinfunction "D")
			(pintype "passive")
		)
	)
)
